# S9S_MB_2U (Grand Teton) — schematic netlist excerpt (pin names and nets, part order shuffled) for the footprints in the layout excerpt that follows; sources: Cadence DE-HDL packaged netlist, KiCad conversion of 03242023_DA0F0TMBIJ0_F0T_Motherboard_J_brd_V01_OCP.brd

PR395  Q_RES  0 5% CHIP  pkg 0402LF  page 263 : A = P3V3_AUX ; B = PVCC1_AUX
PR1314  Q_RES  11.3K 0.1% CHIP  pkg 0402LF  page 299 : A = PVPP_HBM_CPU1_FB ; B = SH_PVPP_HBM_CPU1_N

(kicad_pcb
	(version 20260206)
	(generator "pcbnew")
	(generator_version "10.0")
	(general
		(thickness 1.6)
		(legacy_teardrops no)
	)
	(paper "A4")
	(title_block
		(title "03242023_DA0F0TMBIJ0_F0T_Motherboard_J_brd_V01_OCP.brd")
		(comment 1 "Grand Teton / footprints 3860-3861 of 6105")
	)
	(layers
		(0 "F.Cu" signal "TOP")
		(4 "In1.Cu" signal "GND")
		(6 "In2.Cu" signal "IN1")
		(8 "In3.Cu" signal "GND1")
		(10 "In4.Cu" signal "IN2")
		(12 "In5.Cu" signal "GND2")
		(14 "In6.Cu" signal "IN3")
		(16 "In7.Cu" signal "GND3")
		(18 "In8.Cu" signal "VCC")
		(20 "In9.Cu" signal "VCC1")
		(22 "In10.Cu" signal "GND4")
		(24 "In11.Cu" signal "IN4")
		(26 "In12.Cu" signal "GND5")
		(28 "In13.Cu" signal "IN5")
		(30 "In14.Cu" signal "GND6")
		(32 "In15.Cu" signal "IN6")
		(34 "In16.Cu" signal "GND7")
		(2 "B.Cu" signal "BOTTOM")
		(9 "F.Adhes" user "F.Adhesive")
		(11 "B.Adhes" user "B.Adhesive")
		(13 "F.Paste" user "Package Geometry/Pastemask Top")
		(15 "B.Paste" user "Package Geometry/Pastemask Bottom")
		(5 "F.SilkS" user "Ref Des/Silkscreen Top")
		(7 "B.SilkS" user "Ref Des/Silkscreen Bottom")
		(1 "F.Mask" user "Board Geometry/Soldermask Top")
		(3 "B.Mask" user "Board Geometry/Soldermask Bottom")
		(17 "Dwgs.User" user "User.Drawings")
		(19 "Cmts.User" user "User.Comments")
		(21 "Eco1.User" user "User.Eco1")
		(23 "Eco2.User" user "User.Eco2")
		(25 "Edge.Cuts" user "Board Geometry/Outline")
		(27 "Margin" user)
		(31 "F.CrtYd" user "Package Geometry/Place Bound Top")
		(29 "B.CrtYd" user "Package Geometry/Place Bound Bottom")
		(35 "F.Fab" user "Ref Des/Assembly Top")
		(33 "B.Fab" user "Ref Des/Assembly Bottom")
	)
	(footprint ""
		(layer "F.Cu")
		(at 122.292872 -357.11638 90)
		(property "Reference" "PR1314"
			(at 0 0 90)
			(layer "F.SilkS")
			(hide yes)
			(effects
				(font
					(size 1.27 1.27)
				)
			)
		)
		(property "Value" ""
			(at 0 0 90)
			(layer "F.Fab")
			(effects
				(font
					(size 1.27 1.27)
				)
			)
		)
		(duplicate_pad_numbers_are_jumpers no)
		(fp_line
			(start 0.7874 -0.4064)
			(end 0.7874 0.4064)
			(stroke
				(width 0.1524)
				(type default)
			)
			(layer "F.SilkS")
		)
		(fp_line
			(start -0.7874 -0.4064)
			(end 0.7874 -0.4064)
			(stroke
				(width 0.1524)
				(type default)
			)
			(layer "F.SilkS")
		)
		(fp_line
			(start 0.7874 0.4064)
			(end -0.7874 0.4064)
			(stroke
				(width 0.1524)
				(type default)
			)
			(layer "F.SilkS")
		)
		(fp_line
			(start -0.7874 0.4064)
			(end -0.7874 -0.4064)
			(stroke
				(width 0.1524)
				(type default)
			)
			(layer "F.SilkS")
		)
		(fp_line
			(start -0.12065 -0.305054)
			(end -0.12065 -0.2794)
			(stroke
				(width 0.1)
				(type default)
			)
			(layer "F.Fab")
		)
		(fp_line
			(start -0.67945 -0.305054)
			(end -0.12065 -0.305054)
			(stroke
				(width 0.1)
				(type default)
			)
			(layer "F.Fab")
		)
		(fp_line
			(start 0.67945 -0.3048)
			(end 0.67945 0.3048)
			(stroke
				(width 0.1)
				(type default)
			)
			(layer "F.Fab")
		)
		(fp_line
			(start 0.12065 -0.3048)
			(end 0.67945 -0.3048)
			(stroke
				(width 0.1)
				(type default)
			)
			(layer "F.Fab")
		)
		(fp_line
			(start 0.12065 -0.2794)
			(end 0.12065 -0.3048)
			(stroke
				(width 0.1)
				(type default)
			)
			(layer "F.Fab")
		)
		(fp_line
			(start -0.12065 -0.2794)
			(end 0.12065 -0.2794)
			(stroke
				(width 0.1)
				(type default)
			)
			(layer "F.Fab")
		)
		(fp_line
			(start 0.120396 0.2794)
			(end -0.12065 0.2794)
			(stroke
				(width 0.1)
				(type default)
			)
			(layer "F.Fab")
		)
		(fp_line
			(start -0.12065 0.2794)
			(end -0.12065 0.3048)
			(stroke
				(width 0.1)
				(type default)
			)
			(layer "F.Fab")
		)
		(fp_line
			(start 0.67945 0.3048)
			(end 0.120396 0.3048)
			(stroke
				(width 0.1)
				(type default)
			)
			(layer "F.Fab")
		)
		(fp_line
			(start 0.120396 0.3048)
			(end 0.120396 0.2794)
			(stroke
				(width 0.1)
				(type default)
			)
			(layer "F.Fab")
		)
		(fp_line
			(start -0.12065 0.3048)
			(end -0.67945 0.3048)
			(stroke
				(width 0.1)
				(type default)
			)
			(layer "F.Fab")
		)
		(fp_line
			(start -0.67945 0.3048)
			(end -0.67945 -0.305054)
			(stroke
				(width 0.1)
				(type default)
			)
			(layer "F.Fab")
		)
		(pad "1" smd circle
			(at -0.40005 0 90)
			(size 0 0)
			(layers "F.Cu" "F.Mask" "F.Paste")
			(net "PVPP_HBM_CPU1_FB")
		)
		(pad "2" smd circle
			(at 0.40005 0 90)
			(size 0 0)
			(layers "F.Cu" "F.Mask" "F.Paste")
			(net "SH_PVPP_HBM_CPU1_N")
		)
	)
	(footprint ""
		(layer "F.Cu")
		(at 382.005332 -71.134224 180)
		(property "Reference" "PR395"
			(at 0 0 180)
			(layer "F.SilkS")
			(hide yes)
			(effects
				(font
					(size 1.27 1.27)
				)
			)
		)
		(property "Value" ""
			(at 0 0 180)
			(layer "F.Fab")
			(effects
				(font
					(size 1.27 1.27)
				)
			)
		)
		(duplicate_pad_numbers_are_jumpers no)
		(fp_line
			(start 0.7874 0.4064)
			(end -0.7874 0.4064)
			(stroke
				(width 0.1524)
				(type default)
			)
			(layer "F.SilkS")
		)
		(fp_line
			(start 0.7874 -0.4064)
			(end 0.7874 0.4064)
			(stroke
				(width 0.1524)
				(type default)
			)
			(layer "F.SilkS")
		)
		(fp_line
			(start -0.7874 0.4064)
			(end -0.7874 -0.4064)
			(stroke
				(width 0.1524)
				(type default)
			)
			(layer "F.SilkS")
		)
		(fp_line
			(start -0.7874 -0.4064)
			(end 0.7874 -0.4064)
			(stroke
				(width 0.1524)
				(type default)
			)
			(layer "F.SilkS")
		)
		(fp_line
			(start 0.67945 0.3048)
			(end 0.120396 0.3048)
			(stroke
				(width 0.1)
				(type default)
			)
			(layer "F.Fab")
		)
		(fp_line
			(start 0.67945 -0.3048)
			(end 0.67945 0.3048)
			(stroke
				(width 0.1)
				(type default)
			)
			(layer "F.Fab")
		)
		(fp_line
			(start 0.12065 -0.2794)
			(end 0.12065 -0.3048)
			(stroke
				(width 0.1)
				(type default)
			)
			(layer "F.Fab")
		)
		(fp_line
			(start 0.12065 -0.3048)
			(end 0.67945 -0.3048)
			(stroke
				(width 0.1)
				(type default)
			)
			(layer "F.Fab")
		)
		(fp_line
			(start 0.120396 0.3048)
			(end 0.120396 0.2794)
			(stroke
				(width 0.1)
				(type default)
			)
			(layer "F.Fab")
		)
		(fp_line
			(start 0.120396 0.2794)
			(end -0.12065 0.2794)
			(stroke
				(width 0.1)
				(type default)
			)
			(layer "F.Fab")
		)
		(fp_line
			(start -0.12065 0.3048)
			(end -0.67945 0.3048)
			(stroke
				(width 0.1)
				(type default)
			)
			(layer "F.Fab")
		)
		(fp_line
			(start -0.12065 0.2794)
			(end -0.12065 0.3048)
			(stroke
				(width 0.1)
				(type default)
			)
			(layer "F.Fab")
		)
		(fp_line
			(start -0.12065 -0.2794)
			(end 0.12065 -0.2794)
			(stroke
				(width 0.1)
				(type default)
			)
			(layer "F.Fab")
		)
		(fp_line
			(start -0.12065 -0.305054)
			(end -0.12065 -0.2794)
			(stroke
				(width 0.1)
				(type default)
			)
			(layer "F.Fab")
		)
		(fp_line
			(start -0.67945 0.3048)
			(end -0.67945 -0.305054)
			(stroke
				(width 0.1)
				(type default)
			)
			(layer "F.Fab")
		)
		(fp_line
			(start -0.67945 -0.305054)
			(end -0.12065 -0.305054)
			(stroke
				(width 0.1)
				(type default)
			)
			(layer "F.Fab")
		)
		(pad "1" smd circle
			(at -0.40005 0 180)
			(size 0 0)
			(layers "F.Cu" "F.Mask" "F.Paste")
			(net "P3V3_AUX")
		)
		(pad "2" smd circle
			(at 0.40005 0 180)
			(size 0 0)
			(layers "F.Cu" "F.Mask" "F.Paste")
			(net "PVCC1_AUX")
		)
	)
)
